(kicad_pcb
	(version 20260206)
	(generator "pcbnew")
	(generator_version "10.0")
	(general
		(thickness 1.6)
		(legacy_teardrops no)
	)
	(paper "A4")
	(title_block
		(title "v2-tray-backplane — ms_tbp_v2.brd")
		(comment 1 "Open CloudServer (Microsoft) / footprint 154 of 164 (J2), pads 122-162 of 162")
	)
	(layers
		(0 "F.Cu" signal "TOP")
		(4 "In1.Cu" signal "LYR2")
		(6 "In2.Cu" signal "LYR3")
		(8 "In3.Cu" signal "LYR4")
		(10 "In4.Cu" signal "LYR5")
		(12 "In5.Cu" signal "LYR6")
		(14 "In6.Cu" signal "LYR7")
		(2 "B.Cu" signal "BOTTOM")
		(9 "F.Adhes" user "F.Adhesive")
		(11 "B.Adhes" user "B.Adhesive")
		(13 "F.Paste" user "Package Geometry/Pastemask Top")
		(15 "B.Paste" user "Package Geometry/Pastemask Bottom")
		(5 "F.SilkS" user "Ref Des/Silkscreen Top")
		(7 "B.SilkS" user "Ref Des/Silkscreen Bottom")
		(1 "F.Mask" user "Board Geometry/Soldermask Top")
		(3 "B.Mask" user "Board Geometry/Soldermask Bottom")
		(17 "Dwgs.User" user "User.Drawings")
		(19 "Cmts.User" user "User.Comments")
		(21 "Eco1.User" user "User.Eco1")
		(23 "Eco2.User" user "User.Eco2")
		(25 "Edge.Cuts" user "Board Geometry/Outline")
		(27 "Margin" user)
		(31 "F.CrtYd" user "Package Geometry/Place Bound Top")
		(29 "B.CrtYd" user "Package Geometry/Place Bound Bottom")
		(35 "F.Fab" user "Ref Des/Assembly Top")
		(33 "B.Fab" user "Ref Des/Assembly Bottom")
	)
	(footprint ""
		(layer "F.Cu")
		(at -375.079999 30.959999 90)
		(property "Reference" "J2"
			(at 17.249079 1.136119 0)
			(unlocked yes)
			(layer "F.SilkS")
			(effects
				(font
					(size 0.762 0.5334)
					(thickness 0.1016)
				)
			)
		)
		(property "Value" ""
			(at 0 0 90)
			(layer "F.Fab")
			(effects
				(font
					(size 1.27 1.27)
				)
			)
		)
		(duplicate_pad_numbers_are_jumpers no)
		(pad "120" smd circle
			(at 5.715 4.445 90)
			(size 0.635 0.635)
			(layers "F.Cu" "F.Mask" "F.Paste")
			(net "GND")
		)
		(pad "121" smd circle
			(at 6.985 -4.445 90)
			(size 0.635 0.635)
			(layers "F.Cu" "F.Mask" "F.Paste")
			(net "PCIE_T2B_B1_RX_DN<0>")
		)
		(pad "122" smd circle
			(at 6.985 -3.175 90)
			(size 0.635 0.635)
			(layers "F.Cu" "F.Mask" "F.Paste")
			(net "GND")
		)
		(pad "123" smd circle
			(at 6.985 -1.905 90)
			(size 0.635 0.635)
			(layers "F.Cu" "F.Mask" "F.Paste")
			(net "PCIE_T2B_B1_RX_DN<8>")
		)
		(pad "124" smd circle
			(at 6.985 -0.635 90)
			(size 0.635 0.635)
			(layers "F.Cu" "F.Mask" "F.Paste")
			(net "GND")
		)
		(pad "125" smd circle
			(at 6.985 0.635 90)
			(size 0.635 0.635)
			(layers "F.Cu" "F.Mask" "F.Paste")
			(net "PCIE_B2T_B1_TX_DN<0>")
		)
		(pad "126" smd circle
			(at 6.985 1.905 90)
			(size 0.635 0.635)
			(layers "F.Cu" "F.Mask" "F.Paste")
			(net "GND")
		)
		(pad "127" smd circle
			(at 6.985 3.175 90)
			(size 0.635 0.635)
			(layers "F.Cu" "F.Mask" "F.Paste")
			(net "PCIE_B2T_B1_TX_DN<8>")
		)
		(pad "128" smd circle
			(at 6.985 4.445 90)
			(size 0.635 0.635)
			(layers "F.Cu" "F.Mask" "F.Paste")
			(net "GND")
		)
		(pad "129" smd circle
			(at 8.255 -4.445 90)
			(size 0.635 0.635)
			(layers "F.Cu" "F.Mask" "F.Paste")
			(net "GND")
		)
		(pad "130" smd circle
			(at 8.255 -3.175 90)
			(size 0.635 0.635)
			(layers "F.Cu" "F.Mask" "F.Paste")
			(net "CLK_100M_B1_P<0>")
		)
		(pad "131" smd circle
			(at 8.255 -1.905 90)
			(size 0.635 0.635)
			(layers "F.Cu" "F.Mask" "F.Paste")
			(net "GND")
		)
		(pad "132" smd circle
			(at 8.255 -0.635 90)
			(size 0.635 0.635)
			(layers "F.Cu" "F.Mask" "F.Paste")
			(net "CLK_100M_B1_P<1>")
		)
		(pad "133" smd circle
			(at 8.255 0.635 90)
			(size 0.635 0.635)
			(layers "F.Cu" "F.Mask" "F.Paste")
			(net "GND")
		)
		(pad "134" smd circle
			(at 8.255 1.905 90)
			(size 0.635 0.635)
			(layers "F.Cu" "F.Mask" "F.Paste")
			(net "CLK_100M_B1_P<2>")
		)
		(pad "135" smd circle
			(at 8.255 3.175 90)
			(size 0.635 0.635)
			(layers "F.Cu" "F.Mask" "F.Paste")
			(net "GND")
		)
		(pad "136" smd circle
			(at 8.255 4.445 90)
			(size 0.635 0.635)
			(layers "F.Cu" "F.Mask" "F.Paste")
			(net "CLK_100M_B1_P<3>")
		)
		(pad "137" smd circle
			(at 9.525 -4.445 90)
			(size 0.635 0.635)
			(layers "F.Cu" "F.Mask" "F.Paste")
			(net "P12V_MEZZ_B1")
		)
		(pad "138" smd circle
			(at 9.525 -3.175 90)
			(size 0.635 0.635)
			(layers "F.Cu" "F.Mask" "F.Paste")
			(net "CLK_100M_B1_N<0>")
		)
		(pad "139" smd circle
			(at 9.525 -1.905 90)
			(size 0.635 0.635)
			(layers "F.Cu" "F.Mask" "F.Paste")
			(net "GND")
		)
		(pad "140" smd circle
			(at 9.525 -0.635 90)
			(size 0.635 0.635)
			(layers "F.Cu" "F.Mask" "F.Paste")
			(net "CLK_100M_B1_N<1>")
		)
		(pad "141" smd circle
			(at 9.525 0.635 90)
			(size 0.635 0.635)
			(layers "F.Cu" "F.Mask" "F.Paste")
			(net "GND")
		)
		(pad "142" smd circle
			(at 9.525 1.905 90)
			(size 0.635 0.635)
			(layers "F.Cu" "F.Mask" "F.Paste")
			(net "CLK_100M_B1_N<2>")
		)
		(pad "143" smd circle
			(at 9.525 3.175 90)
			(size 0.635 0.635)
			(layers "F.Cu" "F.Mask" "F.Paste")
			(net "PCIE_RESET_B1_N<2>")
		)
		(pad "144" smd circle
			(at 9.525 4.445 90)
			(size 0.635 0.635)
			(layers "F.Cu" "F.Mask" "F.Paste")
			(net "CLK_100M_B1_N<3>")
		)
		(pad "145" smd circle
			(at 10.795 -4.445 90)
			(size 0.635 0.635)
			(layers "F.Cu" "F.Mask" "F.Paste")
			(net "P12V_MEZZ_B1")
		)
		(pad "146" smd circle
			(at 10.795 -3.175 90)
			(size 0.635 0.635)
			(layers "F.Cu" "F.Mask" "F.Paste")
			(net "GND")
		)
		(pad "147" smd circle
			(at 10.795 -1.905 90)
			(size 0.635 0.635)
			(layers "F.Cu" "F.Mask" "F.Paste")
			(net "GND")
		)
		(pad "148" smd circle
			(at 10.795 -0.635 90)
			(size 0.635 0.635)
			(layers "F.Cu" "F.Mask" "F.Paste")
			(net "PCIE_CFG_B1_ID1")
		)
		(pad "149" smd circle
			(at 10.795 0.635 90)
			(size 0.635 0.635)
			(layers "F.Cu" "F.Mask" "F.Paste")
			(net "PCIE_CFG_B1_ID0")
		)
		(pad "150" smd circle
			(at 10.795 1.905 90)
			(size 0.635 0.635)
			(layers "F.Cu" "F.Mask" "F.Paste")
			(net "PCIE_RESET_B1_N<0>")
		)
		(pad "151" smd circle
			(at 10.795 3.175 90)
			(size 0.635 0.635)
			(layers "F.Cu" "F.Mask" "F.Paste")
			(net "PCIE_RESET_B1_N<1>")
		)
		(pad "152" smd circle
			(at 10.795 4.445 90)
			(size 0.635 0.635)
			(layers "F.Cu" "F.Mask" "F.Paste")
			(net "PCIE_RESET_B1_N<3>")
		)
		(pad "153" smd circle
			(at 12.065 -4.445 90)
			(size 0.635 0.635)
			(layers "F.Cu" "F.Mask" "F.Paste")
			(net "P12V_MEZZ_B1")
		)
		(pad "154" smd circle
			(at 12.065 -3.175 90)
			(size 0.635 0.635)
			(layers "F.Cu" "F.Mask" "F.Paste")
			(net "P12V_MEZZ_B1")
		)
		(pad "155" smd circle
			(at 12.065 -1.905 90)
			(size 0.635 0.635)
			(layers "F.Cu" "F.Mask" "F.Paste")
			(net "P12V_MEZZ_B1")
		)
		(pad "156" smd circle
			(at 12.065 -0.635 90)
			(size 0.635 0.635)
			(layers "F.Cu" "F.Mask" "F.Paste")
			(net "MEZZ_B1_SCL")
		)
		(pad "157" smd circle
			(at 12.065 0.635 90)
			(size 0.635 0.635)
			(layers "F.Cu" "F.Mask" "F.Paste")
			(net "MEZZ_B1_EN")
		)
		(pad "158" smd circle
			(at 12.065 1.905 90)
			(size 0.635 0.635)
			(layers "F.Cu" "F.Mask" "F.Paste")
			(net "MEZZ_B1_SDA")
		)
		(pad "159" smd circle
			(at 12.065 3.175 90)
			(size 0.635 0.635)
			(layers "F.Cu" "F.Mask" "F.Paste")
			(net "PCIE_WAKE_B1_N")
		)
		(pad "160" smd circle
			(at 12.065 4.445 90)
			(size 0.635 0.635)
			(layers "F.Cu" "F.Mask" "F.Paste")
			(net "MEZZ_PRESENT_B1_N")
		)
	)
)
